# T6G (Grand Teton) — schematic netlist excerpt (pin names and nets, part order shuffled) for the footprints in the layout excerpt that follows; sources: Cadence DE-HDL packaged netlist, KiCad conversion of 04192023_DAF0TMB3IC0_F0TG_MB_C_brd_V02_OCP.brd

J90  SCONN56_123276793  SCONN56_1-2327679-3 IO  pkg CON_F56S2H4D_P0-6W4-6_LUHXA  page 145
  GND_A1  = GND
  GND_A2  = GND
  GND_A3  = GND
  GND_A4  = GND
  GND_A5  = GND
  GND_A6  = GND
  SMBCLK  = SMB_E1S_3V3AUX_ISO_SCL
  SMBDAT  = SMB_E1S_3V3AUX_ISO_SDA
  \smbrst#\  = RST_SMB_E1S_0_N
  \led#_activity\  = FM_LED_ACTIVE_E1S_0_BUF
  \perst1#_clkreq#\  = E1S_0_PERST1_CLKREQ_N
  \prsnt0#\  = E1S_0_PRSNT_N
  GND_A13  = GND
  REFCLK_N1  = TP_CLK_100M_E1S_0_DN
  REFCLK_P1  = TP_CLK_100M_E1S_0_DP
  GND_A16  = GND
  PER_N0  = P3E_CPU0_P4_RX_DP<0>
  PER_P0  = P3E_CPU0_P4_RX_DN<0>
  GND_A19  = GND
  PER_N1  = P3E_CPU0_P4_RX_DP<1>
  PER_P1  = P3E_CPU0_P4_RX_DN<1>
  GND_A22  = GND
  PER_N2  = P3E_CPU0_P4_RX_DP<2>
  PER_P2  = P3E_CPU0_P4_RX_DN<2>
  GND_A25  = GND
  PER_N3  = P3E_CPU0_P4_RX_DP<3>
  PER_P3  = P3E_CPU0_P4_RX_DN<3>
  GND_A28  = GND
  P12V_B1  = P12V_E1S_0_R
  P12V_B2  = P12V_E1S_0_R
  P12V_B3  = P12V_E1S_0_R
  P12V_B4  = P12V_E1S_0_R
  P12V_B5  = P12V_E1S_0_R
  P12V_B6  = P12V_E1S_0_R
  MFG  = TP_E1S_0_MFG
  RFU  = TP_E1S_0_RFU
  \dualporten#\  = PU_E1S_0_DUALPORT_EN_N
  \perst0#\  = RST_PCIE_E1S_PERST_N
  P3V3_AUX  = P3V3_E1S_0
  PWRDIS  = E1S_0_PWRDIS
  GND_B13  = GND
  REFCLK_N0  = CLK_100M_CPU0_CLK12_DN
  REFCLK_P0  = CLK_100M_CPU0_CLK12_DP
  GND_B16  = GND
  PET_N0  = P3E_CPU0_P4_TX_C_DP<0>
  PET_P0  = P3E_CPU0_P4_TX_C_DN<0>
  GND_B19  = GND
  PET_N1  = P3E_CPU0_P4_TX_C_DP<1>
  PET_P1  = P3E_CPU0_P4_TX_C_DN<1>
  GND_B22  = GND
  PET_N2  = P3E_CPU0_P4_TX_C_DP<2>
  PET_P2  = P3E_CPU0_P4_TX_C_DN<2>
  GND_B25  = GND
  PET_N3  = P3E_CPU0_P4_TX_C_DN<3>
  PET_P3  = P3E_CPU0_P4_TX_C_DP<3>
  GND_B28  = GND
  G1  = GND
  G2  = GND

(kicad_pcb
	(version 20260206)
	(generator "pcbnew")
	(generator_version "10.0")
	(general
		(thickness 1.6)
		(legacy_teardrops no)
	)
	(paper "A4")
	(title_block
		(title "04192023_DAF0TMB3IC0_F0TG_MB_C_brd_V02_OCP.brd")
		(comment 1 "Grand Teton / footprint 3138 of 8354 (J90), pads 1-46 of 60")
	)
	(layers
		(0 "F.Cu" signal "TOP")
		(4 "In1.Cu" signal "GND")
		(6 "In2.Cu" signal "IN1")
		(8 "In3.Cu" signal "GND1")
		(10 "In4.Cu" signal "IN2")
		(12 "In5.Cu" signal "GND2")
		(14 "In6.Cu" signal "IN3")
		(16 "In7.Cu" signal "GND3")
		(18 "In8.Cu" signal "VCC")
		(20 "In9.Cu" signal "VCC1")
		(22 "In10.Cu" signal "GND4")
		(24 "In11.Cu" signal "IN4")
		(26 "In12.Cu" signal "GND5")
		(28 "In13.Cu" signal "IN5")
		(30 "In14.Cu" signal "GND6")
		(32 "In15.Cu" signal "IN6")
		(34 "In16.Cu" signal "GND7")
		(2 "B.Cu" signal "BOTTOM")
		(9 "F.Adhes" user "F.Adhesive")
		(11 "B.Adhes" user "B.Adhesive")
		(13 "F.Paste" user "Package Geometry/Pastemask Top")
		(15 "B.Paste" user "Package Geometry/Pastemask Bottom")
		(5 "F.SilkS" user "Ref Des/Silkscreen Top")
		(7 "B.SilkS" user "Ref Des/Silkscreen Bottom")
		(1 "F.Mask" user "Board Geometry/Soldermask Top")
		(3 "B.Mask" user "Board Geometry/Soldermask Bottom")
		(17 "Dwgs.User" user "User.Drawings")
		(19 "Cmts.User" user "User.Comments")
		(21 "Eco1.User" user "User.Eco1")
		(23 "Eco2.User" user "User.Eco2")
		(25 "Edge.Cuts" user "Board Geometry/Outline")
		(27 "Margin" user)
		(31 "F.CrtYd" user "Package Geometry/Place Bound Top")
		(29 "B.CrtYd" user "Package Geometry/Place Bound Bottom")
		(35 "F.Fab" user "Ref Des/Assembly Top")
		(33 "B.Fab" user "Ref Des/Assembly Bottom")
	)
	(footprint ""
		(layer "F.Cu")
		(at 234.300014 -50.55997 180)
		(property "Reference" "J90"
			(at 4.181094 -11.365484 90)
			(unlocked yes)
			(layer "F.SilkS")
			(effects
				(font
					(size 0.7874 0.5842)
					(thickness 0.1524)
				)
			)
		)
		(property "Value" ""
			(at 0 0 180)
			(layer "F.Fab")
			(effects
				(font
					(size 1.27 1.27)
				)
			)
		)
		(duplicate_pad_numbers_are_jumpers no)
		(pad "" np_thru_hole circle
			(at -1.75006 -9.815068 90)
			(size 1.1176 1.1176)
			(drill 1.1176)
			(layers "*.Cu" "*.Mask")
			(clearance 0.381)
			(thermal_gap 0.381)
		)
		(pad "" np_thru_hole circle
			(at 0 9.815068 90)
			(size 1.1176 1.1176)
			(drill 1.1176)
			(layers "*.Cu" "*.Mask")
			(clearance 0.381)
			(thermal_gap 0.381)
		)
		(pad "A1" smd rect
			(at 2.29997 -7.994904 90)
			(size 0.381 1.27)
			(layers "F.Cu" "F.Mask" "F.Paste")
			(net "GND")
		)
		(pad "A2" smd rect
			(at 2.29997 -7.394956 90)
			(size 0.381 1.27)
			(layers "F.Cu" "F.Mask" "F.Paste")
			(net "GND")
		)
		(pad "A3" smd rect
			(at 2.29997 -6.795008 90)
			(size 0.381 1.27)
			(layers "F.Cu" "F.Mask" "F.Paste")
			(net "GND")
		)
		(pad "A4" smd rect
			(at 2.29997 -6.19506 90)
			(size 0.381 1.27)
			(layers "F.Cu" "F.Mask" "F.Paste")
			(net "GND")
		)
		(pad "A5" smd rect
			(at 2.29997 -5.595112 90)
			(size 0.381 1.27)
			(layers "F.Cu" "F.Mask" "F.Paste")
			(net "GND")
		)
		(pad "A6" smd rect
			(at 2.29997 -4.99491 90)
			(size 0.381 1.27)
			(layers "F.Cu" "F.Mask" "F.Paste")
			(net "GND")
		)
		(pad "A7" smd rect
			(at 2.29997 -4.394962 90)
			(size 0.381 1.27)
			(layers "F.Cu" "F.Mask" "F.Paste")
			(net "SMB_E1S_3V3AUX_ISO_SCL")
		)
		(pad "A8" smd rect
			(at 2.29997 -3.795014 90)
			(size 0.381 1.27)
			(layers "F.Cu" "F.Mask" "F.Paste")
			(net "SMB_E1S_3V3AUX_ISO_SDA")
		)
		(pad "A9" smd rect
			(at 2.29997 -3.195066 90)
			(size 0.381 1.27)
			(layers "F.Cu" "F.Mask" "F.Paste")
			(net "RST_SMB_E1S_0_N")
		)
		(pad "A10" smd rect
			(at 2.29997 -2.595118 90)
			(size 0.381 1.27)
			(layers "F.Cu" "F.Mask" "F.Paste")
			(net "FM_LED_ACTIVE_E1S_0_BUF")
		)
		(pad "A11" smd rect
			(at 2.29997 -1.994916 90)
			(size 0.381 1.27)
			(layers "F.Cu" "F.Mask" "F.Paste")
			(net "E1S_0_PERST1_CLKREQ_N")
		)
		(pad "A12" smd rect
			(at 2.29997 -1.394968 90)
			(size 0.381 1.27)
			(layers "F.Cu" "F.Mask" "F.Paste")
			(net "E1S_0_PRSNT_N")
		)
		(pad "A13" smd rect
			(at 2.29997 -0.79502 90)
			(size 0.381 1.27)
			(layers "F.Cu" "F.Mask" "F.Paste")
			(net "GND")
		)
		(pad "A14" smd rect
			(at 2.29997 -0.195072 90)
			(size 0.381 1.27)
			(layers "F.Cu" "F.Mask" "F.Paste")
			(net "TP_CLK_100M_E1S_0_DN")
		)
		(pad "A15" smd rect
			(at 2.29997 0.404876 90)
			(size 0.381 1.27)
			(layers "F.Cu" "F.Mask" "F.Paste")
			(net "TP_CLK_100M_E1S_0_DP")
		)
		(pad "A16" smd rect
			(at 2.29997 1.005078 90)
			(size 0.381 1.27)
			(layers "F.Cu" "F.Mask" "F.Paste")
			(net "GND")
		)
		(pad "A17" smd rect
			(at 2.29997 1.605026 90)
			(size 0.381 1.27)
			(layers "F.Cu" "F.Mask" "F.Paste")
			(net "P3E_CPU0_P4_RX_DP<0>")
		)
		(pad "A18" smd rect
			(at 2.29997 2.204974 90)
			(size 0.381 1.27)
			(layers "F.Cu" "F.Mask" "F.Paste")
			(net "P3E_CPU0_P4_RX_DN<0>")
		)
		(pad "A19" smd rect
			(at 2.29997 2.804922 90)
			(size 0.381 1.27)
			(layers "F.Cu" "F.Mask" "F.Paste")
			(net "GND")
		)
		(pad "A20" smd rect
			(at 2.29997 3.405124 90)
			(size 0.381 1.27)
			(layers "F.Cu" "F.Mask" "F.Paste")
			(net "P3E_CPU0_P4_RX_DP<1>")
		)
		(pad "A21" smd rect
			(at 2.29997 4.005072 90)
			(size 0.381 1.27)
			(layers "F.Cu" "F.Mask" "F.Paste")
			(net "P3E_CPU0_P4_RX_DN<1>")
		)
		(pad "A22" smd rect
			(at 2.29997 4.60502 90)
			(size 0.381 1.27)
			(layers "F.Cu" "F.Mask" "F.Paste")
			(net "GND")
		)
		(pad "A23" smd rect
			(at 2.29997 5.204968 90)
			(size 0.381 1.27)
			(layers "F.Cu" "F.Mask" "F.Paste")
			(net "P3E_CPU0_P4_RX_DP<2>")
		)
		(pad "A24" smd rect
			(at 2.29997 5.804916 90)
			(size 0.381 1.27)
			(layers "F.Cu" "F.Mask" "F.Paste")
			(net "P3E_CPU0_P4_RX_DN<2>")
		)
		(pad "A25" smd rect
			(at 2.29997 6.405118 90)
			(size 0.381 1.27)
			(layers "F.Cu" "F.Mask" "F.Paste")
			(net "GND")
		)
		(pad "A26" smd rect
			(at 2.29997 7.005066 90)
			(size 0.381 1.27)
			(layers "F.Cu" "F.Mask" "F.Paste")
			(net "P3E_CPU0_P4_RX_DP<3>")
		)
		(pad "A27" smd rect
			(at 2.29997 7.605014 90)
			(size 0.381 1.27)
			(layers "F.Cu" "F.Mask" "F.Paste")
			(net "P3E_CPU0_P4_RX_DN<3>")
		)
		(pad "A28" smd rect
			(at 2.29997 8.204962 90)
			(size 0.381 1.27)
			(layers "F.Cu" "F.Mask" "F.Paste")
			(net "GND")
		)
		(pad "B1" smd rect
			(at -2.29997 -7.994904 90)
			(size 0.381 1.27)
			(layers "F.Cu" "F.Mask" "F.Paste")
			(net "P12V_E1S_0_R")
		)
		(pad "B2" smd rect
			(at -2.29997 -7.394956 90)
			(size 0.381 1.27)
			(layers "F.Cu" "F.Mask" "F.Paste")
			(net "P12V_E1S_0_R")
		)
		(pad "B3" smd rect
			(at -2.29997 -6.795008 90)
			(size 0.381 1.27)
			(layers "F.Cu" "F.Mask" "F.Paste")
			(net "P12V_E1S_0_R")
		)
		(pad "B4" smd rect
			(at -2.29997 -6.19506 90)
			(size 0.381 1.27)
			(layers "F.Cu" "F.Mask" "F.Paste")
			(net "P12V_E1S_0_R")
		)
		(pad "B5" smd rect
			(at -2.29997 -5.595112 90)
			(size 0.381 1.27)
			(layers "F.Cu" "F.Mask" "F.Paste")
			(net "P12V_E1S_0_R")
		)
		(pad "B6" smd rect
			(at -2.29997 -4.99491 90)
			(size 0.381 1.27)
			(layers "F.Cu" "F.Mask" "F.Paste")
			(net "P12V_E1S_0_R")
		)
		(pad "B7" smd rect
			(at -2.29997 -4.394962 90)
			(size 0.381 1.27)
			(layers "F.Cu" "F.Mask" "F.Paste")
			(net "TP_E1S_0_MFG")
		)
		(pad "B8" smd rect
			(at -2.29997 -3.795014 90)
			(size 0.381 1.27)
			(layers "F.Cu" "F.Mask" "F.Paste")
			(net "TP_E1S_0_RFU")
		)
		(pad "B9" smd rect
			(at -2.29997 -3.195066 90)
			(size 0.381 1.27)
			(layers "F.Cu" "F.Mask" "F.Paste")
			(net "PU_E1S_0_DUALPORT_EN_N")
		)
		(pad "B10" smd rect
			(at -2.29997 -2.595118 90)
			(size 0.381 1.27)
			(layers "F.Cu" "F.Mask" "F.Paste")
			(net "RST_PCIE_E1S_PERST_N")
		)
		(pad "B11" smd rect
			(at -2.29997 -1.994916 90)
			(size 0.381 1.27)
			(layers "F.Cu" "F.Mask" "F.Paste")
			(net "P3V3_E1S_0")
		)
		(pad "B12" smd rect
			(at -2.29997 -1.394968 90)
			(size 0.381 1.27)
			(layers "F.Cu" "F.Mask" "F.Paste")
			(net "E1S_0_PWRDIS")
		)
		(pad "B13" smd rect
			(at -2.29997 -0.79502 90)
			(size 0.381 1.27)
			(layers "F.Cu" "F.Mask" "F.Paste")
			(net "GND")
		)
		(pad "B14" smd rect
			(at -2.29997 -0.195072 90)
			(size 0.381 1.27)
			(layers "F.Cu" "F.Mask" "F.Paste")
			(net "CLK_100M_CPU0_CLK12_DN")
		)
		(pad "B15" smd rect
			(at -2.29997 0.404876 90)
			(size 0.381 1.27)
			(layers "F.Cu" "F.Mask" "F.Paste")
			(net "CLK_100M_CPU0_CLK12_DP")
		)
		(pad "B16" smd rect
			(at -2.29997 1.005078 90)
			(size 0.381 1.27)
			(layers "F.Cu" "F.Mask" "F.Paste")
			(net "GND")
		)
	)
)
